(kicad_pcb
	(version 20260206)
	(generator "pcbnew")
	(generator_version "10.0")
	(general
		(thickness 1.6)
		(legacy_teardrops no)
	)
	(paper "A4")
	(title_block
		(title "04192023_DAF0TMB3IC0_F0TG_MB_C_brd_V02_OCP.brd")
		(comment 1 "Grand Teton / footprints 4270-4274 of 8354")
	)
	(layers
		(0 "F.Cu" signal "TOP")
		(4 "In1.Cu" signal "GND")
		(6 "In2.Cu" signal "IN1")
		(8 "In3.Cu" signal "GND1")
		(10 "In4.Cu" signal "IN2")
		(12 "In5.Cu" signal "GND2")
		(14 "In6.Cu" signal "IN3")
		(16 "In7.Cu" signal "GND3")
		(18 "In8.Cu" signal "VCC")
		(20 "In9.Cu" signal "VCC1")
		(22 "In10.Cu" signal "GND4")
		(24 "In11.Cu" signal "IN4")
		(26 "In12.Cu" signal "GND5")
		(28 "In13.Cu" signal "IN5")
		(30 "In14.Cu" signal "GND6")
		(32 "In15.Cu" signal "IN6")
		(34 "In16.Cu" signal "GND7")
		(2 "B.Cu" signal "BOTTOM")
		(9 "F.Adhes" user "F.Adhesive")
		(11 "B.Adhes" user "B.Adhesive")
		(13 "F.Paste" user "Package Geometry/Pastemask Top")
		(15 "B.Paste" user "Package Geometry/Pastemask Bottom")
		(5 "F.SilkS" user "Ref Des/Silkscreen Top")
		(7 "B.SilkS" user "Ref Des/Silkscreen Bottom")
		(1 "F.Mask" user "Board Geometry/Soldermask Top")
		(3 "B.Mask" user "Board Geometry/Soldermask Bottom")
		(17 "Dwgs.User" user "User.Drawings")
		(19 "Cmts.User" user "User.Comments")
		(21 "Eco1.User" user "User.Eco1")
		(23 "Eco2.User" user "User.Eco2")
		(25 "Edge.Cuts" user "Board Geometry/Outline")
		(27 "Margin" user)
		(31 "F.CrtYd" user "Package Geometry/Place Bound Top")
		(29 "B.CrtYd" user "Package Geometry/Place Bound Bottom")
		(35 "F.Fab" user "Ref Des/Assembly Top")
		(33 "B.Fab" user "Ref Des/Assembly Bottom")
	)
	(footprint ""
		(layer "F.Cu")
		(at 302.523398 -431.2539)
		(property "Reference" "R4140"
			(at 0 0 0)
			(layer "F.SilkS")
			(hide yes)
			(effects
				(font
					(size 1.27 1.27)
				)
			)
		)
		(property "Value" ""
			(at 0 0 0)
			(layer "F.Fab")
			(effects
				(font
					(size 1.27 1.27)
				)
			)
		)
		(duplicate_pad_numbers_are_jumpers no)
		(fp_line
			(start -0.7874 -0.4064)
			(end 0.7874 -0.4064)
			(stroke
				(width 0.1524)
				(type default)
			)
			(layer "F.SilkS")
		)
		(fp_line
			(start -0.7874 0.4064)
			(end -0.7874 -0.4064)
			(stroke
				(width 0.1524)
				(type default)
			)
			(layer "F.SilkS")
		)
		(fp_line
			(start 0.7874 -0.4064)
			(end 0.7874 0.4064)
			(stroke
				(width 0.1524)
				(type default)
			)
			(layer "F.SilkS")
		)
		(fp_line
			(start 0.7874 0.4064)
			(end -0.7874 0.4064)
			(stroke
				(width 0.1524)
				(type default)
			)
			(layer "F.SilkS")
		)
		(fp_line
			(start -0.67945 -0.305054)
			(end -0.12065 -0.305054)
			(stroke
				(width 0.1)
				(type default)
			)
			(layer "F.Fab")
		)
		(fp_line
			(start -0.67945 0.3048)
			(end -0.67945 -0.305054)
			(stroke
				(width 0.1)
				(type default)
			)
			(layer "F.Fab")
		)
		(fp_line
			(start -0.12065 -0.305054)
			(end -0.12065 -0.2794)
			(stroke
				(width 0.1)
				(type default)
			)
			(layer "F.Fab")
		)
		(fp_line
			(start -0.12065 -0.2794)
			(end 0.12065 -0.2794)
			(stroke
				(width 0.1)
				(type default)
			)
			(layer "F.Fab")
		)
		(fp_line
			(start -0.12065 0.2794)
			(end -0.12065 0.3048)
			(stroke
				(width 0.1)
				(type default)
			)
			(layer "F.Fab")
		)
		(fp_line
			(start -0.12065 0.3048)
			(end -0.67945 0.3048)
			(stroke
				(width 0.1)
				(type default)
			)
			(layer "F.Fab")
		)
		(fp_line
			(start 0.120396 0.2794)
			(end -0.12065 0.2794)
			(stroke
				(width 0.1)
				(type default)
			)
			(layer "F.Fab")
		)
		(fp_line
			(start 0.120396 0.3048)
			(end 0.120396 0.2794)
			(stroke
				(width 0.1)
				(type default)
			)
			(layer "F.Fab")
		)
		(fp_line
			(start 0.12065 -0.3048)
			(end 0.67945 -0.3048)
			(stroke
				(width 0.1)
				(type default)
			)
			(layer "F.Fab")
		)
		(fp_line
			(start 0.12065 -0.2794)
			(end 0.12065 -0.3048)
			(stroke
				(width 0.1)
				(type default)
			)
			(layer "F.Fab")
		)
		(fp_line
			(start 0.67945 -0.3048)
			(end 0.67945 0.3048)
			(stroke
				(width 0.1)
				(type default)
			)
			(layer "F.Fab")
		)
		(fp_line
			(start 0.67945 0.3048)
			(end 0.120396 0.3048)
			(stroke
				(width 0.1)
				(type default)
			)
			(layer "F.Fab")
		)
		(pad "1" smd circle
			(at -0.40005 0)
			(size 0 0)
			(layers "F.Cu" "F.Mask" "F.Paste")
			(net "P3V3_AUX")
		)
		(pad "2" smd circle
			(at 0.40005 0)
			(size 0 0)
			(layers "F.Cu" "F.Mask" "F.Paste")
			(net "GPU_3V3IO_RSVD3_FFU_ISO")
		)
	)
	(footprint ""
		(layer "F.Cu")
		(at 240.421922 -148.6408)
		(property "Reference" "R1648"
			(at 0 0 0)
			(layer "F.SilkS")
			(hide yes)
			(effects
				(font
					(size 1.27 1.27)
				)
			)
		)
		(property "Value" ""
			(at 0 0 0)
			(layer "F.Fab")
			(effects
				(font
					(size 1.27 1.27)
				)
			)
		)
		(duplicate_pad_numbers_are_jumpers no)
		(fp_line
			(start -0.7874 -0.4064)
			(end 0.7874 -0.4064)
			(stroke
				(width 0.1524)
				(type default)
			)
			(layer "F.SilkS")
		)
		(fp_line
			(start -0.7874 0.4064)
			(end -0.7874 -0.4064)
			(stroke
				(width 0.1524)
				(type default)
			)
			(layer "F.SilkS")
		)
		(fp_line
			(start 0.7874 -0.4064)
			(end 0.7874 0.4064)
			(stroke
				(width 0.1524)
				(type default)
			)
			(layer "F.SilkS")
		)
		(fp_line
			(start 0.7874 0.4064)
			(end -0.7874 0.4064)
			(stroke
				(width 0.1524)
				(type default)
			)
			(layer "F.SilkS")
		)
		(fp_line
			(start -0.67945 -0.305054)
			(end -0.12065 -0.305054)
			(stroke
				(width 0.1)
				(type default)
			)
			(layer "F.Fab")
		)
		(fp_line
			(start -0.67945 0.3048)
			(end -0.67945 -0.305054)
			(stroke
				(width 0.1)
				(type default)
			)
			(layer "F.Fab")
		)
		(fp_line
			(start -0.12065 -0.305054)
			(end -0.12065 -0.2794)
			(stroke
				(width 0.1)
				(type default)
			)
			(layer "F.Fab")
		)
		(fp_line
			(start -0.12065 -0.2794)
			(end 0.12065 -0.2794)
			(stroke
				(width 0.1)
				(type default)
			)
			(layer "F.Fab")
		)
		(fp_line
			(start -0.12065 0.2794)
			(end -0.12065 0.3048)
			(stroke
				(width 0.1)
				(type default)
			)
			(layer "F.Fab")
		)
		(fp_line
			(start -0.12065 0.3048)
			(end -0.67945 0.3048)
			(stroke
				(width 0.1)
				(type default)
			)
			(layer "F.Fab")
		)
		(fp_line
			(start 0.120396 0.2794)
			(end -0.12065 0.2794)
			(stroke
				(width 0.1)
				(type default)
			)
			(layer "F.Fab")
		)
		(fp_line
			(start 0.120396 0.3048)
			(end 0.120396 0.2794)
			(stroke
				(width 0.1)
				(type default)
			)
			(layer "F.Fab")
		)
		(fp_line
			(start 0.12065 -0.3048)
			(end 0.67945 -0.3048)
			(stroke
				(width 0.1)
				(type default)
			)
			(layer "F.Fab")
		)
		(fp_line
			(start 0.12065 -0.2794)
			(end 0.12065 -0.3048)
			(stroke
				(width 0.1)
				(type default)
			)
			(layer "F.Fab")
		)
		(fp_line
			(start 0.67945 -0.3048)
			(end 0.67945 0.3048)
			(stroke
				(width 0.1)
				(type default)
			)
			(layer "F.Fab")
		)
		(fp_line
			(start 0.67945 0.3048)
			(end 0.120396 0.3048)
			(stroke
				(width 0.1)
				(type default)
			)
			(layer "F.Fab")
		)
		(pad "1" smd circle
			(at -0.40005 0)
			(size 0 0)
			(layers "F.Cu" "F.Mask" "F.Paste")
			(net "JTAG_CPU0_R_TDI")
		)
		(pad "2" smd circle
			(at 0.40005 0)
			(size 0 0)
			(layers "F.Cu" "F.Mask" "F.Paste")
			(net "JTAG_CPU0_TDI")
		)
	)
	(footprint ""
		(layer "F.Cu")
		(at 152.849834 -324.763892 180)
		(property "Reference" "R736"
			(at 0 0 180)
			(layer "F.SilkS")
			(hide yes)
			(effects
				(font
					(size 1.27 1.27)
				)
			)
		)
		(property "Value" ""
			(at 0 0 180)
			(layer "F.Fab")
			(effects
				(font
					(size 1.27 1.27)
				)
			)
		)
		(duplicate_pad_numbers_are_jumpers no)
		(fp_line
			(start 0.7874 0.4064)
			(end -0.7874 0.4064)
			(stroke
				(width 0.1524)
				(type default)
			)
			(layer "F.SilkS")
		)
		(fp_line
			(start 0.7874 -0.4064)
			(end 0.7874 0.4064)
			(stroke
				(width 0.1524)
				(type default)
			)
			(layer "F.SilkS")
		)
		(fp_line
			(start -0.7874 0.4064)
			(end -0.7874 -0.4064)
			(stroke
				(width 0.1524)
				(type default)
			)
			(layer "F.SilkS")
		)
		(fp_line
			(start -0.7874 -0.4064)
			(end 0.7874 -0.4064)
			(stroke
				(width 0.1524)
				(type default)
			)
			(layer "F.SilkS")
		)
		(fp_line
			(start 0.67945 0.3048)
			(end 0.120396 0.3048)
			(stroke
				(width 0.1)
				(type default)
			)
			(layer "F.Fab")
		)
		(fp_line
			(start 0.67945 -0.3048)
			(end 0.67945 0.3048)
			(stroke
				(width 0.1)
				(type default)
			)
			(layer "F.Fab")
		)
		(fp_line
			(start 0.12065 -0.2794)
			(end 0.12065 -0.3048)
			(stroke
				(width 0.1)
				(type default)
			)
			(layer "F.Fab")
		)
		(fp_line
			(start 0.12065 -0.3048)
			(end 0.67945 -0.3048)
			(stroke
				(width 0.1)
				(type default)
			)
			(layer "F.Fab")
		)
		(fp_line
			(start 0.120396 0.3048)
			(end 0.120396 0.2794)
			(stroke
				(width 0.1)
				(type default)
			)
			(layer "F.Fab")
		)
		(fp_line
			(start 0.120396 0.2794)
			(end -0.12065 0.2794)
			(stroke
				(width 0.1)
				(type default)
			)
			(layer "F.Fab")
		)
		(fp_line
			(start -0.12065 0.3048)
			(end -0.67945 0.3048)
			(stroke
				(width 0.1)
				(type default)
			)
			(layer "F.Fab")
		)
		(fp_line
			(start -0.12065 0.2794)
			(end -0.12065 0.3048)
			(stroke
				(width 0.1)
				(type default)
			)
			(layer "F.Fab")
		)
		(fp_line
			(start -0.12065 -0.2794)
			(end 0.12065 -0.2794)
			(stroke
				(width 0.1)
				(type default)
			)
			(layer "F.Fab")
		)
		(fp_line
			(start -0.12065 -0.305054)
			(end -0.12065 -0.2794)
			(stroke
				(width 0.1)
				(type default)
			)
			(layer "F.Fab")
		)
		(fp_line
			(start -0.67945 0.3048)
			(end -0.67945 -0.305054)
			(stroke
				(width 0.1)
				(type default)
			)
			(layer "F.Fab")
		)
		(fp_line
			(start -0.67945 -0.305054)
			(end -0.12065 -0.305054)
			(stroke
				(width 0.1)
				(type default)
			)
			(layer "F.Fab")
		)
		(pad "1" smd circle
			(at -0.40005 0 180)
			(size 0 0)
			(layers "F.Cu" "F.Mask" "F.Paste")
			(net "PVDD18_S5_P1")
		)
		(pad "2" smd circle
			(at 0.40005 0 180)
			(size 0 0)
			(layers "F.Cu" "F.Mask" "F.Paste")
			(net "PD_ESPI_CPU1_CLK2")
		)
	)
	(footprint ""
		(layer "F.Cu")
		(at 525.408906 -298.384214 90)
		(property "Reference" "X1"
			(at -1.830578 2.823718 0)
			(unlocked yes)
			(layer "F.SilkS")
			(effects
				(font
					(size 0.7874 0.5842)
					(thickness 0.1524)
				)
				(justify left)
			)
		)
		(property "Value" ""
			(at 0 0 90)
			(layer "F.Fab")
			(effects
				(font
					(size 1.27 1.27)
				)
			)
		)
		(property "User Part Number" "N_A"
			(at 1.30175 1.27 180)
			(unlocked yes)
			(layer "Cmts.User")
			(hide yes)
			(effects
				(font
					(size 0.635 0.4064)
					(thickness 0.1524)
				)
			)
		)
		(property "Device Type" "TP_TDR_4P_FTS_TH-TP_TDR_4P_DIP,EMPTY,TP15"
			(at 1.30175 1.27 180)
			(unlocked yes)
			(layer "F.Fab")
			(hide yes)
			(effects
				(font
					(size 0.635 0.4064)
					(thickness 0.1524)
				)
			)
		)
		(duplicate_pad_numbers_are_jumpers no)
		(fp_line
			(start 2.54 -1.27)
			(end 0 -1.27)
			(stroke
				(width 0.1524)
				(type default)
			)
			(layer "F.SilkS")
		)
		(fp_line
			(start 0 -1.27)
			(end 0 -0.635)
			(stroke
				(width 0.1524)
				(type default)
			)
			(layer "F.SilkS")
		)
		(fp_line
			(start 2.54 -1.1303)
			(end 2.54 -1.27)
			(stroke
				(width 0.1524)
				(type default)
			)
			(layer "F.SilkS")
		)
		(fp_line
			(start 0 0.635)
			(end 0 1.905)
			(stroke
				(width 0.1524)
				(type default)
			)
			(layer "F.SilkS")
		)
		(fp_line
			(start 2.54 1.4097)
			(end 2.54 1.1303)
			(stroke
				(width 0.1524)
				(type default)
			)
			(layer "F.SilkS")
		)
		(fp_line
			(start 0 3.175)
			(end 0 3.81)
			(stroke
				(width 0.1524)
				(type default)
			)
			(layer "F.SilkS")
		)
		(fp_line
			(start 2.54 3.81)
			(end 2.54 3.6703)
			(stroke
				(width 0.1524)
				(type default)
			)
			(layer "F.SilkS")
		)
		(fp_line
			(start 0 3.81)
			(end 2.54 3.81)
			(stroke
				(width 0.1524)
				(type default)
			)
			(layer "F.SilkS")
		)
		(fp_poly
			(pts
				(xy -0.761746 0) (xy -2.285746 0.762) (xy -2.285746 -0.762)
			)
			(stroke
				(width 0)
				(type default)
			)
			(fill yes)
			(layer "F.SilkS")
		)
		(fp_line
			(start 2.54 -1.27)
			(end 0 -1.27)
			(stroke
				(width 0.1)
				(type default)
			)
			(layer "F.Fab")
		)
		(fp_line
			(start 0 -1.27)
			(end 0 3.81)
			(stroke
				(width 0.1)
				(type default)
			)
			(layer "F.Fab")
		)
		(fp_line
			(start 2.54 3.81)
			(end 2.54 -1.27)
			(stroke
				(width 0.1)
				(type default)
			)
			(layer "F.Fab")
		)
		(fp_line
			(start 0 3.81)
			(end 2.54 3.81)
			(stroke
				(width 0.1)
				(type default)
			)
			(layer "F.Fab")
		)
		(fp_poly
			(pts
				(xy -0.761746 0) (xy -2.285746 -0.762) (xy -2.285746 0.762)
			)
			(stroke
				(width 0)
				(type default)
			)
			(fill yes)
			(layer "F.Fab")
		)
		(pad "1" thru_hole circle
			(at 0 0 90)
			(size 1.0033 1.0033)
			(drill 0.249936)
			(layers "*.Cu" "*.Mask")
			(remove_unused_layers no)
			(net "TDR_DIFF_80_TOP_DP")
			(clearance 0.10795)
			(thermal_gap 0.10795)
			(padstack
				(mode front_inner_back)
				(layer "Inner"
					(shape circle)
					(size 0.8001 0.8001)
					(clearance 0.1524)
				)
				(layer "B.Cu"
					(shape circle)
					(size 1.0033 1.0033)
					(clearance 0.10795)
				)
			)
		)
		(pad "2" thru_hole circle
			(at 2.54 0 90)
			(size 1.9939 1.9939)
			(drill 0.249936)
			(layers "*.Cu" "*.Mask")
			(remove_unused_layers no)
			(net "T1_GND")
			(clearance 0.10795)
			(thermal_gap 0.10795)
			(padstack
				(mode front_inner_back)
				(layer "Inner"
					(shape circle)
					(size 0.8001 0.8001)
					(clearance 0.1524)
				)
				(layer "B.Cu"
					(shape circle)
					(size 1.9939 1.9939)
					(clearance 0.10795)
				)
			)
		)
		(pad "3" thru_hole circle
			(at 2.54 2.54 90)
			(size 1.9939 1.9939)
			(drill 0.249936)
			(layers "*.Cu" "*.Mask")
			(remove_unused_layers no)
			(net "T1_GND")
			(clearance 0.10795)
			(thermal_gap 0.10795)
			(padstack
				(mode front_inner_back)
				(layer "Inner"
					(shape circle)
					(size 0.8001 0.8001)
					(clearance 0.1524)
				)
				(layer "B.Cu"
					(shape circle)
					(size 1.9939 1.9939)
					(clearance 0.10795)
				)
			)
		)
		(pad "4" thru_hole circle
			(at 0 2.54 90)
			(size 1.0033 1.0033)
			(drill 0.249936)
			(layers "*.Cu" "*.Mask")
			(remove_unused_layers no)
			(net "TDR_DIFF_80_TOP_DN")
			(clearance 0.10795)
			(thermal_gap 0.10795)
			(padstack
				(mode front_inner_back)
				(layer "Inner"
					(shape circle)
					(size 0.8001 0.8001)
					(clearance 0.1524)
				)
				(layer "B.Cu"
					(shape circle)
					(size 1.0033 1.0033)
					(clearance 0.10795)
				)
			)
		)
	)
	(footprint ""
		(layer "F.Cu")
		(at 195.2498 -137.668 90)
		(property "Reference" "R6855"
			(at 0 0 90)
			(layer "F.SilkS")
			(hide yes)
			(effects
				(font
					(size 1.27 1.27)
				)
			)
		)
		(property "Value" ""
			(at 0 0 90)
			(layer "F.Fab")
			(effects
				(font
					(size 1.27 1.27)
				)
			)
		)
		(duplicate_pad_numbers_are_jumpers no)
		(fp_line
			(start 0.7874 -0.4064)
			(end 0.7874 0.4064)
			(stroke
				(width 0.1524)
				(type default)
			)
			(layer "F.SilkS")
		)
		(fp_line
			(start -0.7874 -0.4064)
			(end 0.7874 -0.4064)
			(stroke
				(width 0.1524)
				(type default)
			)
			(layer "F.SilkS")
		)
		(fp_line
			(start 0.7874 0.4064)
			(end -0.7874 0.4064)
			(stroke
				(width 0.1524)
				(type default)
			)
			(layer "F.SilkS")
		)
		(fp_line
			(start -0.7874 0.4064)
			(end -0.7874 -0.4064)
			(stroke
				(width 0.1524)
				(type default)
			)
			(layer "F.SilkS")
		)
		(fp_line
			(start -0.12065 -0.305054)
			(end -0.12065 -0.2794)
			(stroke
				(width 0.1)
				(type default)
			)
			(layer "F.Fab")
		)
		(fp_line
			(start -0.67945 -0.305054)
			(end -0.12065 -0.305054)
			(stroke
				(width 0.1)
				(type default)
			)
			(layer "F.Fab")
		)
		(fp_line
			(start 0.67945 -0.3048)
			(end 0.67945 0.3048)
			(stroke
				(width 0.1)
				(type default)
			)
			(layer "F.Fab")
		)
		(fp_line
			(start 0.12065 -0.3048)
			(end 0.67945 -0.3048)
			(stroke
				(width 0.1)
				(type default)
			)
			(layer "F.Fab")
		)
		(fp_line
			(start 0.12065 -0.2794)
			(end 0.12065 -0.3048)
			(stroke
				(width 0.1)
				(type default)
			)
			(layer "F.Fab")
		)
		(fp_line
			(start -0.12065 -0.2794)
			(end 0.12065 -0.2794)
			(stroke
				(width 0.1)
				(type default)
			)
			(layer "F.Fab")
		)
		(fp_line
			(start 0.120396 0.2794)
			(end -0.12065 0.2794)
			(stroke
				(width 0.1)
				(type default)
			)
			(layer "F.Fab")
		)
		(fp_line
			(start -0.12065 0.2794)
			(end -0.12065 0.3048)
			(stroke
				(width 0.1)
				(type default)
			)
			(layer "F.Fab")
		)
		(fp_line
			(start 0.67945 0.3048)
			(end 0.120396 0.3048)
			(stroke
				(width 0.1)
				(type default)
			)
			(layer "F.Fab")
		)
		(fp_line
			(start 0.120396 0.3048)
			(end 0.120396 0.2794)
			(stroke
				(width 0.1)
				(type default)
			)
			(layer "F.Fab")
		)
		(fp_line
			(start -0.12065 0.3048)
			(end -0.67945 0.3048)
			(stroke
				(width 0.1)
				(type default)
			)
			(layer "F.Fab")
		)
		(fp_line
			(start -0.67945 0.3048)
			(end -0.67945 -0.305054)
			(stroke
				(width 0.1)
				(type default)
			)
			(layer "F.Fab")
		)
		(pad "1" smd circle
			(at -0.40005 0 90)
			(size 0 0)
			(layers "F.Cu" "F.Mask" "F.Paste")
			(net "P0V9_RETIMER_CPU1_EN_R2")
		)
		(pad "2" smd circle
			(at 0.40005 0 90)
			(size 0 0)
			(layers "F.Cu" "F.Mask" "F.Paste")
			(net "P0V9_RETIMER_CPU1_EN")
		)
	)
)
